# T6G (Grand Teton) — schematic netlist excerpt (pin names and nets, part order shuffled) for the footprints in the layout excerpt that follows; sources: Cadence DE-HDL packaged netlist, KiCad conversion of 04192023_DAF0TMB3IC0_F0TG_MB_C_brd_V02_OCP.brd

PR505  Q_RES  1.5 1% EMPTY  pkg 0402LF  page 199 : A = SW_PVDDCR_SOC_P0_SW3_RC ; B = GND
R964  Q_RES  1K 1% CHIP  pkg 0201LF  page 276 : A = P1V8_CPU0_RT_1D ; B = RT_CPU0_P0_ADDR3
R6194  Q_RES  0 5% CHIP  pkg 0201LF  page 180 : A = USB2_CPU0_P0_HUB1_R_DP ; B = USB2_HUB_EXT_DP

(kicad_pcb
	(version 20260206)
	(generator "pcbnew")
	(generator_version "10.0")
	(general
		(thickness 1.6)
		(legacy_teardrops no)
	)
	(paper "A4")
	(title_block
		(title "04192023_DAF0TMB3IC0_F0TG_MB_C_brd_V02_OCP.brd")
		(comment 1 "Grand Teton / footprints 4618-4620 of 8354")
	)
	(layers
		(0 "F.Cu" signal "TOP")
		(4 "In1.Cu" signal "GND")
		(6 "In2.Cu" signal "IN1")
		(8 "In3.Cu" signal "GND1")
		(10 "In4.Cu" signal "IN2")
		(12 "In5.Cu" signal "GND2")
		(14 "In6.Cu" signal "IN3")
		(16 "In7.Cu" signal "GND3")
		(18 "In8.Cu" signal "VCC")
		(20 "In9.Cu" signal "VCC1")
		(22 "In10.Cu" signal "GND4")
		(24 "In11.Cu" signal "IN4")
		(26 "In12.Cu" signal "GND5")
		(28 "In13.Cu" signal "IN5")
		(30 "In14.Cu" signal "GND6")
		(32 "In15.Cu" signal "IN6")
		(34 "In16.Cu" signal "GND7")
		(2 "B.Cu" signal "BOTTOM")
		(9 "F.Adhes" user "F.Adhesive")
		(11 "B.Adhes" user "B.Adhesive")
		(13 "F.Paste" user "Package Geometry/Pastemask Top")
		(15 "B.Paste" user "Package Geometry/Pastemask Bottom")
		(5 "F.SilkS" user "Ref Des/Silkscreen Top")
		(7 "B.SilkS" user "Ref Des/Silkscreen Bottom")
		(1 "F.Mask" user "Board Geometry/Soldermask Top")
		(3 "B.Mask" user "Board Geometry/Soldermask Bottom")
		(17 "Dwgs.User" user "User.Drawings")
		(19 "Cmts.User" user "User.Comments")
		(21 "Eco1.User" user "User.Eco1")
		(23 "Eco2.User" user "User.Eco2")
		(25 "Edge.Cuts" user "Board Geometry/Outline")
		(27 "Margin" user)
		(31 "F.CrtYd" user "Package Geometry/Place Bound Top")
		(29 "B.CrtYd" user "Package Geometry/Place Bound Bottom")
		(35 "F.Fab" user "Ref Des/Assembly Top")
		(33 "B.Fab" user "Ref Des/Assembly Bottom")
	)
	(footprint ""
		(layer "F.Cu")
		(at 136.50468 -29.01442 -90)
		(property "Reference" "R6194"
			(at 0 0 270)
			(layer "F.SilkS")
			(hide yes)
			(effects
				(font
					(size 1.27 1.27)
				)
			)
		)
		(property "Value" ""
			(at 0 0 270)
			(layer "F.Fab")
			(effects
				(font
					(size 1.27 1.27)
				)
			)
		)
		(duplicate_pad_numbers_are_jumpers no)
		(fp_line
			(start -0.32512 0.175006)
			(end -0.32512 -0.175006)
			(stroke
				(width 0.1)
				(type default)
			)
			(layer "F.Fab")
		)
		(fp_line
			(start 0.32512 0.175006)
			(end -0.32512 0.175006)
			(stroke
				(width 0.1)
				(type default)
			)
			(layer "F.Fab")
		)
		(fp_line
			(start -0.32512 -0.175006)
			(end 0.32512 -0.175006)
			(stroke
				(width 0.1)
				(type default)
			)
			(layer "F.Fab")
		)
		(fp_line
			(start 0.32512 -0.175006)
			(end 0.32512 0.175006)
			(stroke
				(width 0.1)
				(type default)
			)
			(layer "F.Fab")
		)
		(pad "1" smd rect
			(at -0.2667 0 270)
			(size 0.3048 0.381)
			(layers "F.Cu" "F.Mask" "F.Paste")
			(net "USB2_CPU0_P0_HUB1_R_DP")
		)
		(pad "2" smd rect
			(at 0.2667 0 90)
			(size 0.3048 0.381)
			(layers "F.Cu" "F.Mask" "F.Paste")
			(net "USB2_HUB_EXT_DP")
		)
	)
	(footprint ""
		(layer "F.Cu")
		(at 418.206936 -165.502082 -90)
		(property "Reference" "PR505"
			(at 0 0 270)
			(layer "F.SilkS")
			(hide yes)
			(effects
				(font
					(size 1.27 1.27)
				)
			)
		)
		(property "Value" ""
			(at 0 0 270)
			(layer "F.Fab")
			(effects
				(font
					(size 1.27 1.27)
				)
			)
		)
		(duplicate_pad_numbers_are_jumpers no)
		(fp_line
			(start -0.7874 0.4064)
			(end -0.7874 -0.4064)
			(stroke
				(width 0.1524)
				(type default)
			)
			(layer "F.SilkS")
		)
		(fp_line
			(start 0.7874 0.4064)
			(end -0.7874 0.4064)
			(stroke
				(width 0.1524)
				(type default)
			)
			(layer "F.SilkS")
		)
		(fp_line
			(start -0.7874 -0.4064)
			(end 0.7874 -0.4064)
			(stroke
				(width 0.1524)
				(type default)
			)
			(layer "F.SilkS")
		)
		(fp_line
			(start 0.7874 -0.4064)
			(end 0.7874 0.4064)
			(stroke
				(width 0.1524)
				(type default)
			)
			(layer "F.SilkS")
		)
		(fp_line
			(start -0.67945 0.3048)
			(end -0.67945 -0.305054)
			(stroke
				(width 0.1)
				(type default)
			)
			(layer "F.Fab")
		)
		(fp_line
			(start -0.12065 0.3048)
			(end -0.67945 0.3048)
			(stroke
				(width 0.1)
				(type default)
			)
			(layer "F.Fab")
		)
		(fp_line
			(start 0.120396 0.3048)
			(end 0.120396 0.2794)
			(stroke
				(width 0.1)
				(type default)
			)
			(layer "F.Fab")
		)
		(fp_line
			(start 0.67945 0.3048)
			(end 0.120396 0.3048)
			(stroke
				(width 0.1)
				(type default)
			)
			(layer "F.Fab")
		)
		(fp_line
			(start -0.12065 0.2794)
			(end -0.12065 0.3048)
			(stroke
				(width 0.1)
				(type default)
			)
			(layer "F.Fab")
		)
		(fp_line
			(start 0.120396 0.2794)
			(end -0.12065 0.2794)
			(stroke
				(width 0.1)
				(type default)
			)
			(layer "F.Fab")
		)
		(fp_line
			(start -0.12065 -0.2794)
			(end 0.12065 -0.2794)
			(stroke
				(width 0.1)
				(type default)
			)
			(layer "F.Fab")
		)
		(fp_line
			(start 0.12065 -0.2794)
			(end 0.12065 -0.3048)
			(stroke
				(width 0.1)
				(type default)
			)
			(layer "F.Fab")
		)
		(fp_line
			(start 0.12065 -0.3048)
			(end 0.67945 -0.3048)
			(stroke
				(width 0.1)
				(type default)
			)
			(layer "F.Fab")
		)
		(fp_line
			(start 0.67945 -0.3048)
			(end 0.67945 0.3048)
			(stroke
				(width 0.1)
				(type default)
			)
			(layer "F.Fab")
		)
		(fp_line
			(start -0.67945 -0.305054)
			(end -0.12065 -0.305054)
			(stroke
				(width 0.1)
				(type default)
			)
			(layer "F.Fab")
		)
		(fp_line
			(start -0.12065 -0.305054)
			(end -0.12065 -0.2794)
			(stroke
				(width 0.1)
				(type default)
			)
			(layer "F.Fab")
		)
		(pad "1" smd circle
			(at -0.40005 0 270)
			(size 0 0)
			(layers "F.Cu" "F.Mask" "F.Paste")
			(net "SW_PVDDCR_SOC_P0_SW3_RC")
		)
		(pad "2" smd circle
			(at 0.40005 0 270)
			(size 0 0)
			(layers "F.Cu" "F.Mask" "F.Paste")
			(net "GND")
		)
	)
	(footprint ""
		(layer "F.Cu")
		(at 327.881742 -393.9032 90)
		(property "Reference" "R964"
			(at 0 0 90)
			(layer "F.SilkS")
			(hide yes)
			(effects
				(font
					(size 1.27 1.27)
				)
			)
		)
		(property "Value" ""
			(at 0 0 90)
			(layer "F.Fab")
			(effects
				(font
					(size 1.27 1.27)
				)
			)
		)
		(duplicate_pad_numbers_are_jumpers no)
		(fp_line
			(start 0.32512 -0.175006)
			(end 0.32512 0.175006)
			(stroke
				(width 0.1)
				(type default)
			)
			(layer "F.Fab")
		)
		(fp_line
			(start -0.32512 -0.175006)
			(end 0.32512 -0.175006)
			(stroke
				(width 0.1)
				(type default)
			)
			(layer "F.Fab")
		)
		(fp_line
			(start 0.32512 0.175006)
			(end -0.32512 0.175006)
			(stroke
				(width 0.1)
				(type default)
			)
			(layer "F.Fab")
		)
		(fp_line
			(start -0.32512 0.175006)
			(end -0.32512 -0.175006)
			(stroke
				(width 0.1)
				(type default)
			)
			(layer "F.Fab")
		)
		(pad "1" smd rect
			(at -0.2667 0 90)
			(size 0.3048 0.381)
			(layers "F.Cu" "F.Mask" "F.Paste")
			(net "P1V8_CPU0_RT_1D")
		)
		(pad "2" smd rect
			(at 0.2667 0 270)
			(size 0.3048 0.381)
			(layers "F.Cu" "F.Mask" "F.Paste")
			(net "RT_CPU0_P0_ADDR3")
		)
	)
)
